# T6G (Grand Teton) — schematic netlist excerpt (pin names and nets, part order shuffled) for the footprints in the layout excerpt that follows; sources: Cadence DE-HDL packaged netlist, KiCad conversion of 04192023_DAF0TMB3IC0_F0TG_MB_C_brd_V02_OCP.brd

C3891  Q_CAP  22UF 4V 20% X6S  pkg C0402  page 68 : A = PVDD11_S3_P0 ; B = GND
R748  Q_RES  10K 5% EMPTY  pkg 0402LF  page 76 : A = GND ; B = CPU0_ROM_TYPE_SELECT

(kicad_pcb
	(version 20260206)
	(generator "pcbnew")
	(generator_version "10.0")
	(general
		(thickness 1.6)
		(legacy_teardrops no)
	)
	(paper "A4")
	(title_block
		(title "04192023_DAF0TMB3IC0_F0TG_MB_C_brd_V02_OCP.brd")
		(comment 1 "Grand Teton / footprints 5907-5908 of 8354")
	)
	(layers
		(0 "F.Cu" signal "TOP")
		(4 "In1.Cu" signal "GND")
		(6 "In2.Cu" signal "IN1")
		(8 "In3.Cu" signal "GND1")
		(10 "In4.Cu" signal "IN2")
		(12 "In5.Cu" signal "GND2")
		(14 "In6.Cu" signal "IN3")
		(16 "In7.Cu" signal "GND3")
		(18 "In8.Cu" signal "VCC")
		(20 "In9.Cu" signal "VCC1")
		(22 "In10.Cu" signal "GND4")
		(24 "In11.Cu" signal "IN4")
		(26 "In12.Cu" signal "GND5")
		(28 "In13.Cu" signal "IN5")
		(30 "In14.Cu" signal "GND6")
		(32 "In15.Cu" signal "IN6")
		(34 "In16.Cu" signal "GND7")
		(2 "B.Cu" signal "BOTTOM")
		(9 "F.Adhes" user "F.Adhesive")
		(11 "B.Adhes" user "B.Adhesive")
		(13 "F.Paste" user "Package Geometry/Pastemask Top")
		(15 "B.Paste" user "Package Geometry/Pastemask Bottom")
		(5 "F.SilkS" user "Ref Des/Silkscreen Top")
		(7 "B.SilkS" user "Ref Des/Silkscreen Bottom")
		(1 "F.Mask" user "Board Geometry/Soldermask Top")
		(3 "B.Mask" user "Board Geometry/Soldermask Bottom")
		(17 "Dwgs.User" user "User.Drawings")
		(19 "Cmts.User" user "User.Comments")
		(21 "Eco1.User" user "User.Eco1")
		(23 "Eco2.User" user "User.Eco2")
		(25 "Edge.Cuts" user "Board Geometry/Outline")
		(27 "Margin" user)
		(31 "F.CrtYd" user "Package Geometry/Place Bound Top")
		(29 "B.CrtYd" user "Package Geometry/Place Bound Bottom")
		(35 "F.Fab" user "Ref Des/Assembly Top")
		(33 "B.Fab" user "Ref Des/Assembly Bottom")
	)
	(footprint ""
		(layer "B.Cu")
		(at 403.981158 -329.003152)
		(property "Reference" "R748"
			(at 0 0 0)
			(layer "B.SilkS")
			(hide yes)
			(effects
				(font
					(size 1.27 1.27)
				)
				(justify mirror)
			)
		)
		(property "Value" ""
			(at 0 0 0)
			(layer "B.Fab")
			(effects
				(font
					(size 1.27 1.27)
				)
				(justify mirror)
			)
		)
		(duplicate_pad_numbers_are_jumpers no)
		(fp_line
			(start -0.7874 -0.4064)
			(end -0.7874 0.4064)
			(stroke
				(width 0.1524)
				(type default)
			)
			(layer "B.SilkS")
		)
		(fp_line
			(start -0.7874 0.4064)
			(end 0.7874 0.4064)
			(stroke
				(width 0.1524)
				(type default)
			)
			(layer "B.SilkS")
		)
		(fp_line
			(start 0.7874 -0.4064)
			(end -0.7874 -0.4064)
			(stroke
				(width 0.1524)
				(type default)
			)
			(layer "B.SilkS")
		)
		(fp_line
			(start 0.7874 0.4064)
			(end 0.7874 -0.4064)
			(stroke
				(width 0.1524)
				(type default)
			)
			(layer "B.SilkS")
		)
		(fp_line
			(start -0.67945 -0.3048)
			(end -0.67945 0.3048)
			(stroke
				(width 0.1)
				(type default)
			)
			(layer "B.Fab")
		)
		(fp_line
			(start -0.67945 0.3048)
			(end -0.120396 0.3048)
			(stroke
				(width 0.1)
				(type default)
			)
			(layer "B.Fab")
		)
		(fp_line
			(start -0.12065 -0.3048)
			(end -0.67945 -0.3048)
			(stroke
				(width 0.1)
				(type default)
			)
			(layer "B.Fab")
		)
		(fp_line
			(start -0.12065 -0.2794)
			(end -0.12065 -0.3048)
			(stroke
				(width 0.1)
				(type default)
			)
			(layer "B.Fab")
		)
		(fp_line
			(start -0.120396 0.2794)
			(end 0.12065 0.2794)
			(stroke
				(width 0.1)
				(type default)
			)
			(layer "B.Fab")
		)
		(fp_line
			(start -0.120396 0.3048)
			(end -0.120396 0.2794)
			(stroke
				(width 0.1)
				(type default)
			)
			(layer "B.Fab")
		)
		(fp_line
			(start 0.12065 -0.305054)
			(end 0.12065 -0.2794)
			(stroke
				(width 0.1)
				(type default)
			)
			(layer "B.Fab")
		)
		(fp_line
			(start 0.12065 -0.2794)
			(end -0.12065 -0.2794)
			(stroke
				(width 0.1)
				(type default)
			)
			(layer "B.Fab")
		)
		(fp_line
			(start 0.12065 0.2794)
			(end 0.12065 0.3048)
			(stroke
				(width 0.1)
				(type default)
			)
			(layer "B.Fab")
		)
		(fp_line
			(start 0.12065 0.3048)
			(end 0.67945 0.3048)
			(stroke
				(width 0.1)
				(type default)
			)
			(layer "B.Fab")
		)
		(fp_line
			(start 0.67945 -0.305054)
			(end 0.12065 -0.305054)
			(stroke
				(width 0.1)
				(type default)
			)
			(layer "B.Fab")
		)
		(fp_line
			(start 0.67945 0.3048)
			(end 0.67945 -0.305054)
			(stroke
				(width 0.1)
				(type default)
			)
			(layer "B.Fab")
		)
		(pad "1" smd circle
			(at 0.40005 0 180)
			(size 0 0)
			(layers "B.Cu" "B.Mask" "B.Paste")
			(net "GND")
		)
		(pad "2" smd circle
			(at -0.40005 0 180)
			(size 0 0)
			(layers "B.Cu" "B.Mask" "B.Paste")
			(net "CPU0_ROM_TYPE_SELECT")
		)
	)
	(footprint ""
		(layer "B.Cu")
		(at 364.167166 -261.747762 90)
		(property "Reference" "C3891"
			(at 0 0 90)
			(layer "B.SilkS")
			(hide yes)
			(effects
				(font
					(size 1.27 1.27)
				)
				(justify mirror)
			)
		)
		(property "Value" ""
			(at 0 0 90)
			(layer "B.Fab")
			(effects
				(font
					(size 1.27 1.27)
				)
				(justify mirror)
			)
		)
		(duplicate_pad_numbers_are_jumpers no)
		(fp_line
			(start 0.7874 -0.4064)
			(end -0.7874 -0.4064)
			(stroke
				(width 0.1524)
				(type default)
			)
			(layer "B.SilkS")
		)
		(fp_line
			(start -0.7874 -0.4064)
			(end -0.7874 0.4064)
			(stroke
				(width 0.1524)
				(type default)
			)
			(layer "B.SilkS")
		)
		(fp_line
			(start 0.7874 0.4064)
			(end 0.7874 -0.4064)
			(stroke
				(width 0.1524)
				(type default)
			)
			(layer "B.SilkS")
		)
		(fp_line
			(start -0.7874 0.4064)
			(end 0.7874 0.4064)
			(stroke
				(width 0.1524)
				(type default)
			)
			(layer "B.SilkS")
		)
		(fp_line
			(start 0.67945 -0.305054)
			(end 0.12065 -0.305054)
			(stroke
				(width 0.1)
				(type default)
			)
			(layer "B.Fab")
		)
		(fp_line
			(start 0.12065 -0.305054)
			(end 0.12065 -0.2794)
			(stroke
				(width 0.1)
				(type default)
			)
			(layer "B.Fab")
		)
		(fp_line
			(start -0.12065 -0.3048)
			(end -0.67945 -0.3048)
			(stroke
				(width 0.1)
				(type default)
			)
			(layer "B.Fab")
		)
		(fp_line
			(start -0.67945 -0.3048)
			(end -0.67945 0.3048)
			(stroke
				(width 0.1)
				(type default)
			)
			(layer "B.Fab")
		)
		(fp_line
			(start 0.12065 -0.2794)
			(end -0.12065 -0.2794)
			(stroke
				(width 0.1)
				(type default)
			)
			(layer "B.Fab")
		)
		(fp_line
			(start -0.12065 -0.2794)
			(end -0.12065 -0.3048)
			(stroke
				(width 0.1)
				(type default)
			)
			(layer "B.Fab")
		)
		(fp_line
			(start 0.12065 0.2794)
			(end 0.12065 0.3048)
			(stroke
				(width 0.1)
				(type default)
			)
			(layer "B.Fab")
		)
		(fp_line
			(start -0.120396 0.2794)
			(end 0.12065 0.2794)
			(stroke
				(width 0.1)
				(type default)
			)
			(layer "B.Fab")
		)
		(fp_line
			(start 0.67945 0.3048)
			(end 0.67945 -0.305054)
			(stroke
				(width 0.1)
				(type default)
			)
			(layer "B.Fab")
		)
		(fp_line
			(start 0.12065 0.3048)
			(end 0.67945 0.3048)
			(stroke
				(width 0.1)
				(type default)
			)
			(layer "B.Fab")
		)
		(fp_line
			(start -0.120396 0.3048)
			(end -0.120396 0.2794)
			(stroke
				(width 0.1)
				(type default)
			)
			(layer "B.Fab")
		)
		(fp_line
			(start -0.67945 0.3048)
			(end -0.120396 0.3048)
			(stroke
				(width 0.1)
				(type default)
			)
			(layer "B.Fab")
		)
		(pad "1" smd circle
			(at 0.40005 0 270)
			(size 0 0)
			(layers "B.Cu" "B.Mask" "B.Paste")
			(net "PVDD11_S3_P0")
		)
		(pad "2" smd circle
			(at -0.40005 0 270)
			(size 0 0)
			(layers "B.Cu" "B.Mask" "B.Paste")
			(net "GND")
		)
	)
)
